(kicad_pcb
	(version 20260206)
	(generator "pcbnew")
	(generator_version "10.0")
	(general
		(thickness 1.6)
		(legacy_teardrops no)
	)
	(paper "A4")
	(title_block
		(title "baseboard — 13948-1b.1110WZS1818.brd")
		(comment 1 "Honey Badger (Wiwynn) / footprints 226-233 of 2523")
	)
	(layers
		(0 "F.Cu" signal "TOP")
		(4 "In1.Cu" signal "L2GND")
		(6 "In2.Cu" signal "L3")
		(8 "In3.Cu" signal "L4VCC")
		(10 "In4.Cu" signal "L5VCC")
		(12 "In5.Cu" signal "L6")
		(14 "In6.Cu" signal "L7GND")
		(2 "B.Cu" signal "BOTTOM")
		(9 "F.Adhes" user "F.Adhesive")
		(11 "B.Adhes" user "B.Adhesive")
		(13 "F.Paste" user "Package Geometry/Pastemask Top")
		(15 "B.Paste" user "Package Geometry/Pastemask Bottom")
		(5 "F.SilkS" user "Ref Des/Silkscreen Top")
		(7 "B.SilkS" user "Ref Des/Silkscreen Bottom")
		(1 "F.Mask" user "Board Geometry/Soldermask Top")
		(3 "B.Mask" user "Board Geometry/Soldermask Bottom")
		(17 "Dwgs.User" user "User.Drawings")
		(19 "Cmts.User" user "User.Comments")
		(21 "Eco1.User" user "User.Eco1")
		(23 "Eco2.User" user "User.Eco2")
		(25 "Edge.Cuts" user "Board Geometry/Outline")
		(27 "Margin" user)
		(31 "F.CrtYd" user "Package Geometry/Place Bound Top")
		(29 "B.CrtYd" user "Package Geometry/Place Bound Bottom")
		(35 "F.Fab" user "Ref Des/Assembly Top")
		(33 "B.Fab" user "Ref Des/Assembly Bottom")
	)
	(footprint ""
		(layer "F.Cu")
		(at 174.117 -120.142 90)
		(property "Reference" "PC172"
			(at 0 0 90)
			(layer "F.SilkS")
			(hide yes)
			(effects
				(font
					(size 1.27 1.27)
				)
			)
		)
		(property "Value" "SCD1U50V3KX-GP"
			(at 0 -2.8194 90)
			(unlocked yes)
			(layer "F.Fab")
			(hide yes)
			(effects
				(font
					(size 1.016 1.016)
					(thickness 0.1524)
				)
			)
		)
		(property "Device Type" "C603H36"
			(at 0 -4.3434 90)
			(unlocked yes)
			(layer "F.Fab")
			(hide yes)
			(effects
				(font
					(size 1.016 1.016)
					(thickness 0.1524)
				)
			)
		)
		(duplicate_pad_numbers_are_jumpers no)
		(fp_line
			(start 0.508 0)
			(end -0.508 0)
			(stroke
				(width 0.2032)
				(type default)
			)
			(layer "F.SilkS")
		)
		(fp_rect
			(start -0.5842 1.3335)
			(end 0.5842 -1.3335)
			(stroke
				(width 0)
				(type default)
			)
			(fill no)
			(layer "F.CrtYd")
		)
		(fp_rect
			(start -0.5842 1.3335)
			(end 0.5842 -1.3335)
			(stroke
				(width 0)
				(type default)
			)
			(fill no)
			(layer "F.Fab")
		)
		(pad "1" smd custom
			(at 0 -0.762 90)
			(size 0.2159 0.2159)
			(layers "F.Cu" "F.Mask" "F.Paste")
			(net "P0V9_E_VIN")
			(options
				(clearance outline)
				(anchor circle)
			)
			(primitives
				(gr_poly
					(pts
						(arc
							(start -0.3302 -0.4318)
							(mid -0.402042 -0.402042)
							(end -0.4318 -0.3302)
						)
						(arc
							(start -0.4318 0.3302)
							(mid -0.402042 0.402042)
							(end -0.3302 0.4318)
						)
						(arc
							(start 0.3302 0.4318)
							(mid 0.402042 0.402042)
							(end 0.4318 0.3302)
						)
						(arc
							(start 0.4318 -0.3302)
							(mid 0.402042 -0.402042)
							(end 0.3302 -0.4318)
						)
					)
					(width 0)
					(fill yes)
				)
			)
		)
		(pad "2" smd custom
			(at 0 0.762 90)
			(size 0.2159 0.2159)
			(layers "F.Cu" "F.Mask" "F.Paste")
			(net "GND")
			(options
				(clearance outline)
				(anchor circle)
			)
			(primitives
				(gr_poly
					(pts
						(arc
							(start -0.3302 -0.4318)
							(mid -0.402042 -0.402042)
							(end -0.4318 -0.3302)
						)
						(arc
							(start -0.4318 0.3302)
							(mid -0.402042 0.402042)
							(end -0.3302 0.4318)
						)
						(arc
							(start 0.3302 0.4318)
							(mid 0.402042 0.402042)
							(end 0.4318 0.3302)
						)
						(arc
							(start 0.4318 -0.3302)
							(mid 0.402042 -0.402042)
							(end 0.3302 -0.4318)
						)
					)
					(width 0)
					(fill yes)
				)
			)
		)
	)
	(footprint ""
		(layer "F.Cu")
		(at 208.095596 -118.129812 90)
		(property "Reference" "PG6"
			(at 0 0 90)
			(layer "F.SilkS")
			(hide yes)
			(effects
				(font
					(size 1.27 1.27)
				)
			)
		)
		(property "Value" "COPPER-CLOSE-GP-U"
			(at 0.0762 -2.8702 90)
			(unlocked yes)
			(layer "F.Fab")
			(hide yes)
			(effects
				(font
					(size 1.016 1.016)
					(thickness 0.1524)
				)
			)
		)
		(property "Device Type" "CON2C-U"
			(at 0.0762 -4.3942 90)
			(unlocked yes)
			(layer "F.Fab")
			(hide yes)
			(effects
				(font
					(size 1.016 1.016)
					(thickness 0.1524)
				)
			)
		)
		(duplicate_pad_numbers_are_jumpers no)
		(fp_rect
			(start -0.9398 0.9652)
			(end 0.9398 -0.9652)
			(stroke
				(width 0)
				(type default)
			)
			(fill no)
			(layer "F.CrtYd")
		)
		(fp_rect
			(start -0.9398 0.9652)
			(end 0.9398 -0.9652)
			(stroke
				(width 0)
				(type default)
			)
			(fill no)
			(layer "F.Fab")
		)
		(pad "1" smd custom
			(at 0 -0.5334 90)
			(size 0.17145 0.17145)
			(layers "F.Cu" "F.Mask" "F.Paste")
			(net "AGND_P1V5_E")
			(options
				(clearance outline)
				(anchor circle)
			)
			(primitives
				(gr_poly
					(pts
						(xy -0.127 0.3429) (xy -0.127 0.1651) (xy -0.635 -0.3429) (xy 0.635 -0.3429) (xy 0.127 0.1651)
						(xy 0.127 0.3429)
					)
					(width 0)
					(fill yes)
				)
			)
		)
		(pad "2" smd custom
			(at 0 0.5334 90)
			(size 0.17145 0.17145)
			(layers "F.Cu" "F.Mask" "F.Paste")
			(net "GND")
			(options
				(clearance outline)
				(anchor circle)
			)
			(primitives
				(gr_poly
					(pts
						(xy -0.635 0.3429) (xy -0.127 -0.1651) (xy -0.127 -0.3429) (xy 0.127 -0.3429) (xy 0.127 -0.1651)
						(xy 0.635 0.3429)
					)
					(width 0)
					(fill yes)
				)
			)
		)
	)
	(footprint ""
		(layer "F.Cu")
		(at 278.638 -115.824 180)
		(property "Reference" "PR174"
			(at 0 0 180)
			(layer "F.SilkS")
			(hide yes)
			(effects
				(font
					(size 1.27 1.27)
				)
			)
		)
		(property "Value" "4K02R2F-GP"
			(at 0.064008 -3.993896 180)
			(unlocked yes)
			(layer "F.Fab")
			(hide yes)
			(effects
				(font
					(size 1.016 1.016)
					(thickness 0.1524)
				)
			)
		)
		(property "Device Type" "R402H16"
			(at 0.064008 -5.517896 180)
			(unlocked yes)
			(layer "F.Fab")
			(hide yes)
			(effects
				(font
					(size 1.016 1.016)
					(thickness 0.1524)
				)
			)
		)
		(duplicate_pad_numbers_are_jumpers no)
		(fp_line
			(start 0.508 -0.9398)
			(end -0.508 -0.9398)
			(stroke
				(width 0.1524)
				(type default)
			)
			(layer "F.SilkS")
		)
		(fp_line
			(start -0.508 -0.9398)
			(end -0.508 0.9398)
			(stroke
				(width 0.1524)
				(type default)
			)
			(layer "F.SilkS")
		)
		(fp_rect
			(start -0.508 0.9398)
			(end 0.508 -0.9398)
			(stroke
				(width 0)
				(type default)
			)
			(fill no)
			(layer "F.CrtYd")
		)
		(fp_rect
			(start -0.508 0.9398)
			(end 0.508 -0.9398)
			(stroke
				(width 0)
				(type default)
			)
			(fill no)
			(layer "F.Fab")
		)
		(pad "1" smd custom
			(at 0 -0.4445 180)
			(size 0.1397 0.1397)
			(layers "F.Cu" "F.Mask" "F.Paste")
			(net "P1V8_C_EN_B")
			(options
				(clearance outline)
				(anchor circle)
			)
			(primitives
				(gr_poly
					(pts
						(arc
							(start -0.1778 -0.2794)
							(mid -0.249642 -0.249642)
							(end -0.2794 -0.1778)
						)
						(arc
							(start -0.2794 0.1778)
							(mid -0.249642 0.249642)
							(end -0.1778 0.2794)
						)
						(arc
							(start 0.1778 0.2794)
							(mid 0.249642 0.249642)
							(end 0.2794 0.1778)
						)
						(arc
							(start 0.2794 -0.1778)
							(mid 0.249642 -0.249642)
							(end 0.1778 -0.2794)
						)
					)
					(width 0)
					(fill yes)
				)
			)
		)
		(pad "2" smd custom
			(at 0 0.4445 180)
			(size 0.1397 0.1397)
			(layers "F.Cu" "F.Mask" "F.Paste")
			(net "P3V3_STBY")
			(options
				(clearance outline)
				(anchor circle)
			)
			(primitives
				(gr_poly
					(pts
						(arc
							(start -0.1778 -0.2794)
							(mid -0.249642 -0.249642)
							(end -0.2794 -0.1778)
						)
						(arc
							(start -0.2794 0.1778)
							(mid -0.249642 0.249642)
							(end -0.1778 0.2794)
						)
						(arc
							(start 0.1778 0.2794)
							(mid 0.249642 0.249642)
							(end 0.2794 0.1778)
						)
						(arc
							(start 0.2794 -0.1778)
							(mid 0.249642 -0.249642)
							(end 0.1778 -0.2794)
						)
					)
					(width 0)
					(fill yes)
				)
			)
		)
	)
	(footprint ""
		(layer "F.Cu")
		(at 88.392 -21.463 180)
		(property "Reference" "PC214"
			(at 0 0 180)
			(layer "F.SilkS")
			(hide yes)
			(effects
				(font
					(size 1.27 1.27)
				)
			)
		)
		(property "Value" "SC6800P50V3KX-GP"
			(at 0 -2.8194 180)
			(unlocked yes)
			(layer "F.Fab")
			(hide yes)
			(effects
				(font
					(size 1.016 1.016)
					(thickness 0.1524)
				)
			)
		)
		(property "Device Type" "C603"
			(at 0 -4.3434 180)
			(unlocked yes)
			(layer "F.Fab")
			(hide yes)
			(effects
				(font
					(size 1.016 1.016)
					(thickness 0.1524)
				)
			)
		)
		(duplicate_pad_numbers_are_jumpers no)
		(fp_line
			(start 0.508 0)
			(end -0.508 0)
			(stroke
				(width 0.2032)
				(type default)
			)
			(layer "F.SilkS")
		)
		(fp_rect
			(start -0.5842 1.3335)
			(end 0.5842 -1.3335)
			(stroke
				(width 0)
				(type default)
			)
			(fill no)
			(layer "F.CrtYd")
		)
		(fp_rect
			(start -0.5842 1.3335)
			(end 0.5842 -1.3335)
			(stroke
				(width 0)
				(type default)
			)
			(fill no)
			(layer "F.Fab")
		)
		(pad "1" smd custom
			(at 0 -0.762 180)
			(size 0.2159 0.2159)
			(layers "F.Cu" "F.Mask" "F.Paste")
			(net "VT235_VFB")
			(options
				(clearance outline)
				(anchor circle)
			)
			(primitives
				(gr_poly
					(pts
						(arc
							(start -0.3302 -0.4318)
							(mid -0.402042 -0.402042)
							(end -0.4318 -0.3302)
						)
						(arc
							(start -0.4318 0.3302)
							(mid -0.402042 0.402042)
							(end -0.3302 0.4318)
						)
						(arc
							(start 0.3302 0.4318)
							(mid 0.402042 0.402042)
							(end 0.4318 0.3302)
						)
						(arc
							(start 0.4318 -0.3302)
							(mid 0.402042 -0.402042)
							(end 0.3302 -0.4318)
						)
					)
					(width 0)
					(fill yes)
				)
			)
		)
		(pad "2" smd custom
			(at 0 0.762 180)
			(size 0.2159 0.2159)
			(layers "F.Cu" "F.Mask" "F.Paste")
			(net "VT235_VDES")
			(options
				(clearance outline)
				(anchor circle)
			)
			(primitives
				(gr_poly
					(pts
						(arc
							(start -0.3302 -0.4318)
							(mid -0.402042 -0.402042)
							(end -0.4318 -0.3302)
						)
						(arc
							(start -0.4318 0.3302)
							(mid -0.402042 0.402042)
							(end -0.3302 0.4318)
						)
						(arc
							(start 0.3302 0.4318)
							(mid 0.402042 0.402042)
							(end 0.4318 0.3302)
						)
						(arc
							(start 0.4318 -0.3302)
							(mid 0.402042 -0.402042)
							(end 0.3302 -0.4318)
						)
					)
					(width 0)
					(fill yes)
				)
			)
		)
	)
	(footprint ""
		(layer "F.Cu")
		(at 136.906 -98.806 180)
		(property "Reference" "SC1266"
			(at 0 0 180)
			(layer "F.SilkS")
			(hide yes)
			(effects
				(font
					(size 1.27 1.27)
				)
			)
		)
		(property "Value" "SCD01U10V1KX-GP"
			(at -2.8321 -1.7399 180)
			(unlocked yes)
			(layer "F.Fab")
			(hide yes)
			(effects
				(font
					(size 1.016 1.016)
					(thickness 0.1524)
				)
			)
		)
		(property "Device Type" "C0201H13"
			(at -2.8321 -3.2639 180)
			(unlocked yes)
			(layer "F.Fab")
			(hide yes)
			(effects
				(font
					(size 1.016 1.016)
					(thickness 0.1524)
				)
			)
		)
		(duplicate_pad_numbers_are_jumpers no)
		(fp_rect
			(start -0.2794 0.6477)
			(end 0.2794 -0.6477)
			(stroke
				(width 0)
				(type default)
			)
			(fill no)
			(layer "F.CrtYd")
		)
		(fp_rect
			(start -0.2794 0.6477)
			(end 0.2794 -0.6477)
			(stroke
				(width 0)
				(type default)
			)
			(fill no)
			(layer "F.Fab")
		)
		(pad "1" smd custom
			(at 0 -0.2794 180)
			(size 0.0762 0.0762)
			(layers "F.Cu" "F.Mask" "F.Paste")
			(net "3X24_SAS_TX20_P")
			(options
				(clearance outline)
				(anchor circle)
			)
			(primitives
				(gr_poly
					(pts
						(arc
							(start 0.1524 -0.127)
							(mid 0.137521 -0.162921)
							(end 0.1016 -0.1778)
						)
						(arc
							(start -0.1016 -0.1778)
							(mid -0.137521 -0.162921)
							(end -0.1524 -0.127)
						)
						(arc
							(start -0.1524 0.127)
							(mid -0.137521 0.162921)
							(end -0.1016 0.1778)
						)
						(arc
							(start 0.1016 0.1778)
							(mid 0.137521 0.162921)
							(end 0.1524 0.127)
						)
					)
					(width 0)
					(fill yes)
				)
			)
		)
		(pad "2" smd custom
			(at 0 0.2794 180)
			(size 0.0762 0.0762)
			(layers "F.Cu" "F.Mask" "F.Paste")
			(net "SAS_EXP_GF_TX_DP0")
			(options
				(clearance outline)
				(anchor circle)
			)
			(primitives
				(gr_poly
					(pts
						(arc
							(start 0.1524 -0.127)
							(mid 0.137521 -0.162921)
							(end 0.1016 -0.1778)
						)
						(arc
							(start -0.1016 -0.1778)
							(mid -0.137521 -0.162921)
							(end -0.1524 -0.127)
						)
						(arc
							(start -0.1524 0.127)
							(mid -0.137521 0.162921)
							(end -0.1016 0.1778)
						)
						(arc
							(start 0.1016 0.1778)
							(mid 0.137521 0.162921)
							(end 0.1524 0.127)
						)
					)
					(width 0)
					(fill yes)
				)
			)
		)
	)
	(footprint ""
		(layer "F.Cu")
		(at 345.44 -108.331)
		(property "Reference" "PC6"
			(at 0 0 0)
			(layer "F.SilkS")
			(hide yes)
			(effects
				(font
					(size 1.27 1.27)
				)
			)
		)
		(property "Value" "SCD1U25V3KX-GP"
			(at 0 -2.8194 0)
			(unlocked yes)
			(layer "F.Fab")
			(hide yes)
			(effects
				(font
					(size 1.016 1.016)
					(thickness 0.1524)
				)
			)
		)
		(property "Device Type" "C603H36"
			(at 0 -4.3434 0)
			(unlocked yes)
			(layer "F.Fab")
			(hide yes)
			(effects
				(font
					(size 1.016 1.016)
					(thickness 0.1524)
				)
			)
		)
		(duplicate_pad_numbers_are_jumpers no)
		(fp_line
			(start 0.508 0)
			(end -0.508 0)
			(stroke
				(width 0.2032)
				(type default)
			)
			(layer "F.SilkS")
		)
		(fp_rect
			(start -0.5842 1.3335)
			(end 0.5842 -1.3335)
			(stroke
				(width 0)
				(type default)
			)
			(fill no)
			(layer "F.CrtYd")
		)
		(fp_rect
			(start -0.5842 1.3335)
			(end 0.5842 -1.3335)
			(stroke
				(width 0)
				(type default)
			)
			(fill no)
			(layer "F.Fab")
		)
		(pad "1" smd custom
			(at 0 -0.762)
			(size 0.2159 0.2159)
			(layers "F.Cu" "F.Mask" "F.Paste")
			(net "P5V_STBY_VIN")
			(options
				(clearance outline)
				(anchor circle)
			)
			(primitives
				(gr_poly
					(pts
						(arc
							(start -0.3302 -0.4318)
							(mid -0.402042 -0.402042)
							(end -0.4318 -0.3302)
						)
						(arc
							(start -0.4318 0.3302)
							(mid -0.402042 0.402042)
							(end -0.3302 0.4318)
						)
						(arc
							(start 0.3302 0.4318)
							(mid 0.402042 0.402042)
							(end 0.4318 0.3302)
						)
						(arc
							(start 0.4318 -0.3302)
							(mid 0.402042 -0.402042)
							(end 0.3302 -0.4318)
						)
					)
					(width 0)
					(fill yes)
				)
			)
		)
		(pad "2" smd custom
			(at 0 0.762)
			(size 0.2159 0.2159)
			(layers "F.Cu" "F.Mask" "F.Paste")
			(net "GND")
			(options
				(clearance outline)
				(anchor circle)
			)
			(primitives
				(gr_poly
					(pts
						(arc
							(start -0.3302 -0.4318)
							(mid -0.402042 -0.402042)
							(end -0.4318 -0.3302)
						)
						(arc
							(start -0.4318 0.3302)
							(mid -0.402042 0.402042)
							(end -0.3302 0.4318)
						)
						(arc
							(start 0.3302 0.4318)
							(mid 0.402042 0.402042)
							(end 0.4318 0.3302)
						)
						(arc
							(start 0.4318 -0.3302)
							(mid 0.402042 -0.402042)
							(end 0.3302 -0.4318)
						)
					)
					(width 0)
					(fill yes)
				)
			)
		)
	)
	(footprint ""
		(layer "F.Cu")
		(at 46.670722 -136.498584 90)
		(property "Reference" "SR795"
			(at 0 0 90)
			(layer "F.SilkS")
			(hide yes)
			(effects
				(font
					(size 1.27 1.27)
				)
			)
		)
		(property "Value" "4K7R2F-GP"
			(at 0.064008 -3.993896 90)
			(unlocked yes)
			(layer "F.Fab")
			(hide yes)
			(effects
				(font
					(size 1.016 1.016)
					(thickness 0.1524)
				)
			)
		)
		(property "Device Type" "R402H16"
			(at 0.064008 -5.517896 90)
			(unlocked yes)
			(layer "F.Fab")
			(hide yes)
			(effects
				(font
					(size 1.016 1.016)
					(thickness 0.1524)
				)
			)
		)
		(duplicate_pad_numbers_are_jumpers no)
		(fp_line
			(start 0.508 -0.9398)
			(end -0.508 -0.9398)
			(stroke
				(width 0.1524)
				(type default)
			)
			(layer "F.SilkS")
		)
		(fp_line
			(start -0.508 -0.9398)
			(end -0.508 0.9398)
			(stroke
				(width 0.1524)
				(type default)
			)
			(layer "F.SilkS")
		)
		(fp_rect
			(start -0.508 0.9398)
			(end 0.508 -0.9398)
			(stroke
				(width 0)
				(type default)
			)
			(fill no)
			(layer "F.CrtYd")
		)
		(fp_rect
			(start -0.508 0.9398)
			(end 0.508 -0.9398)
			(stroke
				(width 0)
				(type default)
			)
			(fill no)
			(layer "F.Fab")
		)
		(pad "1" smd custom
			(at 0 -0.4445 90)
			(size 0.1397 0.1397)
			(layers "F.Cu" "F.Mask" "F.Paste")
			(net "P1V8_E")
			(options
				(clearance outline)
				(anchor circle)
			)
			(primitives
				(gr_poly
					(pts
						(arc
							(start -0.1778 -0.2794)
							(mid -0.249642 -0.249642)
							(end -0.2794 -0.1778)
						)
						(arc
							(start -0.2794 0.1778)
							(mid -0.249642 0.249642)
							(end -0.1778 0.2794)
						)
						(arc
							(start 0.1778 0.2794)
							(mid 0.249642 0.249642)
							(end 0.2794 0.1778)
						)
						(arc
							(start 0.2794 -0.1778)
							(mid 0.249642 -0.249642)
							(end 0.1778 -0.2794)
						)
					)
					(width 0)
					(fill yes)
				)
			)
		)
		(pad "2" smd custom
			(at 0 0.4445 90)
			(size 0.1397 0.1397)
			(layers "F.Cu" "F.Mask" "F.Paste")
			(net "RESET_AND_N")
			(options
				(clearance outline)
				(anchor circle)
			)
			(primitives
				(gr_poly
					(pts
						(arc
							(start -0.1778 -0.2794)
							(mid -0.249642 -0.249642)
							(end -0.2794 -0.1778)
						)
						(arc
							(start -0.2794 0.1778)
							(mid -0.249642 0.249642)
							(end -0.1778 0.2794)
						)
						(arc
							(start 0.1778 0.2794)
							(mid 0.249642 0.249642)
							(end 0.2794 0.1778)
						)
						(arc
							(start 0.2794 -0.1778)
							(mid 0.249642 -0.249642)
							(end 0.1778 -0.2794)
						)
					)
					(width 0)
					(fill yes)
				)
			)
		)
	)
	(footprint ""
		(layer "F.Cu")
		(at 198.062596 -121.177812)
		(property "Reference" "PR9017"
			(at 0 0 0)
			(layer "F.SilkS")
			(hide yes)
			(effects
				(font
					(size 1.27 1.27)
				)
			)
		)
		(property "Value" "10KR2F-2-GP"
			(at 0.064008 -3.993896 0)
			(unlocked yes)
			(layer "F.Fab")
			(hide yes)
			(effects
				(font
					(size 1.016 1.016)
					(thickness 0.1524)
				)
			)
		)
		(property "Device Type" "R402H16"
			(at 0.064008 -5.517896 0)
			(unlocked yes)
			(layer "F.Fab")
			(hide yes)
			(effects
				(font
					(size 1.016 1.016)
					(thickness 0.1524)
				)
			)
		)
		(duplicate_pad_numbers_are_jumpers no)
		(fp_line
			(start -0.508 -0.9398)
			(end -0.508 0.9398)
			(stroke
				(width 0.1524)
				(type default)
			)
			(layer "F.SilkS")
		)
		(fp_line
			(start 0.508 -0.9398)
			(end -0.508 -0.9398)
			(stroke
				(width 0.1524)
				(type default)
			)
			(layer "F.SilkS")
		)
		(fp_rect
			(start -0.508 0.9398)
			(end 0.508 -0.9398)
			(stroke
				(width 0)
				(type default)
			)
			(fill no)
			(layer "F.CrtYd")
		)
		(fp_rect
			(start -0.508 0.9398)
			(end 0.508 -0.9398)
			(stroke
				(width 0)
				(type default)
			)
			(fill no)
			(layer "F.Fab")
		)
		(pad "1" smd custom
			(at 0 -0.4445)
			(size 0.1397 0.1397)
			(layers "F.Cu" "F.Mask" "F.Paste")
			(net "P1V5_E_PG")
			(options
				(clearance outline)
				(anchor circle)
			)
			(primitives
				(gr_poly
					(pts
						(arc
							(start -0.1778 -0.2794)
							(mid -0.249642 -0.249642)
							(end -0.2794 -0.1778)
						)
						(arc
							(start -0.2794 0.1778)
							(mid -0.249642 0.249642)
							(end -0.1778 0.2794)
						)
						(arc
							(start 0.1778 0.2794)
							(mid 0.249642 0.249642)
							(end 0.2794 0.1778)
						)
						(arc
							(start 0.2794 -0.1778)
							(mid 0.249642 -0.249642)
							(end 0.1778 -0.2794)
						)
					)
					(width 0)
					(fill yes)
				)
			)
		)
		(pad "2" smd custom
			(at 0 0.4445)
			(size 0.1397 0.1397)
			(layers "F.Cu" "F.Mask" "F.Paste")
			(net "P1V5_E_VRG5")
			(options
				(clearance outline)
				(anchor circle)
			)
			(primitives
				(gr_poly
					(pts
						(arc
							(start -0.1778 -0.2794)
							(mid -0.249642 -0.249642)
							(end -0.2794 -0.1778)
						)
						(arc
							(start -0.2794 0.1778)
							(mid -0.249642 0.249642)
							(end -0.1778 0.2794)
						)
						(arc
							(start 0.1778 0.2794)
							(mid 0.249642 0.249642)
							(end 0.2794 0.1778)
						)
						(arc
							(start 0.2794 -0.1778)
							(mid 0.249642 -0.249642)
							(end 0.1778 -0.2794)
						)
					)
					(width 0)
					(fill yes)
				)
			)
		)
	)
)
